(kicad_pcb
	(version 20260206)
	(generator "pcbnew")
	(generator_version "10.0")
	(general
		(thickness 1.6)
		(legacy_teardrops no)
	)
	(paper "A4")
	(title_block
		(title "panther-plus-userver — 13130-1b_20150205.brd")
		(comment 1 "Honey Badger (Wiwynn) / footprint 282 of 1509 (U13), pads 476-591 of 1283")
	)
	(layers
		(0 "F.Cu" signal "TOP")
		(4 "In1.Cu" signal "L2")
		(6 "In2.Cu" signal "L3")
		(8 "In3.Cu" signal "L4")
		(10 "In4.Cu" signal "L5")
		(12 "In5.Cu" signal "L6")
		(14 "In6.Cu" signal "L7")
		(16 "In7.Cu" signal "L8")
		(18 "In8.Cu" signal "L9")
		(20 "In9.Cu" signal "L10")
		(22 "In10.Cu" signal "L11")
		(2 "B.Cu" signal "BOTTOM")
		(9 "F.Adhes" user "F.Adhesive")
		(11 "B.Adhes" user "B.Adhesive")
		(13 "F.Paste" user "Package Geometry/Pastemask Top")
		(15 "B.Paste" user "Package Geometry/Pastemask Bottom")
		(5 "F.SilkS" user "Ref Des/Silkscreen Top")
		(7 "B.SilkS" user "Ref Des/Silkscreen Bottom")
		(1 "F.Mask" user "Board Geometry/Soldermask Top")
		(3 "B.Mask" user "Board Geometry/Soldermask Bottom")
		(17 "Dwgs.User" user "User.Drawings")
		(19 "Cmts.User" user "User.Comments")
		(21 "Eco1.User" user "User.Eco1")
		(23 "Eco2.User" user "User.Eco2")
		(25 "Edge.Cuts" user "Board Geometry/Outline")
		(27 "Margin" user)
		(31 "F.CrtYd" user "Package Geometry/Place Bound Top")
		(29 "B.CrtYd" user "Package Geometry/Place Bound Bottom")
		(35 "F.Fab" user "Ref Des/Assembly Top")
		(33 "B.Fab" user "Ref Des/Assembly Bottom")
	)
	(footprint ""
		(layer "F.Cu")
		(at 95.849948 -39.200074 180)
		(property "Reference" "U13"
			(at 0 0 180)
			(layer "F.SilkS")
			(hide yes)
			(effects
				(font
					(size 1.27 1.27)
				)
			)
		)
		(property "Value" "AVOTON-GP"
			(at -25.0317 -2.4892 180)
			(unlocked yes)
			(layer "F.Fab")
			(hide yes)
			(effects
				(font
					(size 1.016 1.016)
					(thickness 0.1524)
				)
			)
		)
		(property "Device Type" "BGA1283M3428-3H197"
			(at -25.0317 -4.0132 180)
			(unlocked yes)
			(layer "F.Fab")
			(hide yes)
			(effects
				(font
					(size 1.016 1.016)
					(thickness 0.1524)
				)
			)
		)
		(duplicate_pad_numbers_are_jumpers no)
		(pad "AW64" smd circle
			(at 15.24254 5.60832 180)
			(size 0.3048 0.3048)
			(layers "F.Cu" "F.Mask" "F.Paste")
			(net "XDP_DFX_PORT12")
		)
		(pad "AW66" smd oval
			(at 16.24838 5.83692 180)
			(size 0.3429 0.254)
			(layers "F.Cu" "F.Mask" "F.Paste")
			(net "XDP_DFX_PORT13")
		)
		(pad "AY1" smd oval
			(at -16.24838 6.0452 180)
			(size 0.3429 0.254)
			(layers "F.Cu" "F.Mask" "F.Paste")
			(net "M_A_ECC5")
		)
		(pad "AY2" smd circle
			(at -15.64132 6.39572 180)
			(size 0.3048 0.3048)
			(layers "F.Cu" "F.Mask" "F.Paste")
			(net "M_A_ECC1")
		)
		(pad "AY4" smd circle
			(at -14.89964 6.4008 180)
			(size 0.3048 0.3048)
			(layers "F.Cu" "F.Mask" "F.Paste")
			(net "M_A_ECC0")
		)
		(pad "AY5" smd circle
			(at -14.20368 6.49732 180)
			(size 0.3048 0.3048)
			(layers "F.Cu" "F.Mask" "F.Paste")
			(net "GND")
		)
		(pad "AY8" smd circle
			(at -12.96416 6.42874 180)
			(size 0.3048 0.3048)
			(layers "F.Cu" "F.Mask" "F.Paste")
			(net "M_A_DQ21")
		)
		(pad "AY9" smd circle
			(at -12.20216 6.42874 180)
			(size 0.3048 0.3048)
			(layers "F.Cu" "F.Mask" "F.Paste")
			(net "M_A_DQ16")
		)
		(pad "AY11" smd circle
			(at -11.44016 6.42874 180)
			(size 0.3048 0.3048)
			(layers "F.Cu" "F.Mask" "F.Paste")
			(net "M_A_DQ17")
		)
		(pad "AY12" smd circle
			(at -10.67816 6.42874 180)
			(size 0.3048 0.3048)
			(layers "F.Cu" "F.Mask" "F.Paste")
			(net "GND")
		)
		(pad "AY14" smd circle
			(at -9.91616 6.42874 180)
			(size 0.3048 0.3048)
			(layers "F.Cu" "F.Mask" "F.Paste")
			(net "M_A_DQ22")
		)
		(pad "AY15" smd circle
			(at -9.15416 6.42874 180)
			(size 0.3048 0.3048)
			(layers "F.Cu" "F.Mask" "F.Paste")
			(net "M_A_DQ18")
		)
		(pad "AY19" smd circle
			(at -7.47522 6.53542 180)
			(size 0.3048 0.3048)
			(layers "F.Cu" "F.Mask" "F.Paste")
			(net "PV_VDDR")
		)
		(pad "AY21" smd circle
			(at -6.18998 6.15442 180)
			(size 0.3048 0.3048)
			(layers "F.Cu" "F.Mask" "F.Paste")
			(net "PV_VDDR")
		)
		(pad "AY23" smd circle
			(at -5.48894 6.15442 180)
			(size 0.3048 0.3048)
			(layers "F.Cu" "F.Mask" "F.Paste")
			(net "PV_VDDR")
		)
		(pad "AY29" smd circle
			(at -2.21742 6.15442 180)
			(size 0.3048 0.3048)
			(layers "F.Cu" "F.Mask" "F.Paste")
			(net "M_A_VREF")
		)
		(pad "AY30" smd circle
			(at -1.51638 6.15442 180)
			(size 0.3048 0.3048)
			(layers "F.Cu" "F.Mask" "F.Paste")
			(net "M_A_DQ37")
		)
		(pad "AY37" smd circle
			(at 1.75514 6.15442 180)
			(size 0.3048 0.3048)
			(layers "F.Cu" "F.Mask" "F.Paste")
			(net "P1V0")
		)
		(pad "AY38" smd circle
			(at 2.45618 6.15442 180)
			(size 0.3048 0.3048)
			(layers "F.Cu" "F.Mask" "F.Paste")
			(net "GND")
		)
		(pad "AY45" smd circle
			(at 5.7277 6.15442 180)
			(size 0.3048 0.3048)
			(layers "F.Cu" "F.Mask" "F.Paste")
			(net "GND")
		)
		(pad "AY46" smd circle
			(at 6.42874 6.15442 180)
			(size 0.3048 0.3048)
			(layers "F.Cu" "F.Mask" "F.Paste")
			(net "Net_619")
		)
		(pad "AY52" smd circle
			(at 9.15416 6.18998 180)
			(size 0.3048 0.3048)
			(layers "F.Cu" "F.Mask" "F.Paste")
			(net "GND")
		)
		(pad "AY53" smd circle
			(at 9.91616 6.18998 180)
			(size 0.3048 0.3048)
			(layers "F.Cu" "F.Mask" "F.Paste")
			(net "XDP_CPU_PREQ#")
		)
		(pad "AY55" smd circle
			(at 10.67816 6.18998 180)
			(size 0.3048 0.3048)
			(layers "F.Cu" "F.Mask" "F.Paste")
			(net "GND")
		)
		(pad "AY56" smd circle
			(at 11.44016 6.18998 180)
			(size 0.3048 0.3048)
			(layers "F.Cu" "F.Mask" "F.Paste")
			(net "XDP_DFX_PORT5")
		)
		(pad "AY58" smd circle
			(at 12.20216 6.18998 180)
			(size 0.3048 0.3048)
			(layers "F.Cu" "F.Mask" "F.Paste")
			(net "XDP_DFX_PORT1")
		)
		(pad "AY59" smd circle
			(at 12.96416 6.18998 180)
			(size 0.3048 0.3048)
			(layers "F.Cu" "F.Mask" "F.Paste")
			(net "XDP_DFX_PORT8")
		)
		(pad "AY62" smd circle
			(at 14.20368 6.3119 180)
			(size 0.3048 0.3048)
			(layers "F.Cu" "F.Mask" "F.Paste")
			(net "GND")
		)
		(pad "AY63" smd circle
			(at 14.89964 6.21792 180)
			(size 0.3048 0.3048)
			(layers "F.Cu" "F.Mask" "F.Paste")
			(net "XDP_DFX_PORT6")
		)
		(pad "AY65" smd circle
			(at 15.63878 6.18744 180)
			(size 0.3048 0.3048)
			(layers "F.Cu" "F.Mask" "F.Paste")
			(net "XDP_DFX_PORT14")
		)
		(pad "B10" smd circle
			(at -11.8237 -12.63904 180)
			(size 0.3048 0.3048)
			(layers "F.Cu" "F.Mask" "F.Paste")
			(net "GND")
		)
		(pad "B12" smd circle
			(at -10.8966 -12.64158 180)
			(size 0.3048 0.3048)
			(layers "F.Cu" "F.Mask" "F.Paste")
			(net "M_B_ECC7")
		)
		(pad "B14" smd circle
			(at -9.8679 -12.80668 180)
			(size 0.3048 0.3048)
			(layers "F.Cu" "F.Mask" "F.Paste")
			(net "M_B_DQS_DP8")
		)
		(pad "B17" smd circle
			(at -8.38708 -12.75334 180)
			(size 0.3048 0.3048)
			(layers "F.Cu" "F.Mask" "F.Paste")
			(net "M_B_ECC5")
		)
		(pad "B19" smd circle
			(at -7.32028 -12.63904 180)
			(size 0.3048 0.3048)
			(layers "F.Cu" "F.Mask" "F.Paste")
			(net "M_B_DQ19")
		)
		(pad "B21" smd circle
			(at -6.39572 -12.64158 180)
			(size 0.3048 0.3048)
			(layers "F.Cu" "F.Mask" "F.Paste")
			(net "M_B_DQ22")
		)
		(pad "B23" smd circle
			(at -5.36448 -12.80668 180)
			(size 0.3048 0.3048)
			(layers "F.Cu" "F.Mask" "F.Paste")
			(net "M_B_DQ17")
		)
		(pad "B26" smd circle
			(at -3.8862 -12.75334 180)
			(size 0.3048 0.3048)
			(layers "F.Cu" "F.Mask" "F.Paste")
			(net "GND")
		)
		(pad "B28" smd circle
			(at -2.8194 -12.63904 180)
			(size 0.3048 0.3048)
			(layers "F.Cu" "F.Mask" "F.Paste")
			(net "M_B_DQ15")
		)
		(pad "B30" smd circle
			(at -1.8923 -12.64158 180)
			(size 0.3048 0.3048)
			(layers "F.Cu" "F.Mask" "F.Paste")
			(net "M_B_DQS_DN1")
		)
		(pad "B32" smd circle
			(at -0.8636 -12.80668 180)
			(size 0.3048 0.3048)
			(layers "F.Cu" "F.Mask" "F.Paste")
			(net "M_B_DQ8")
		)
		(pad "B35" smd circle
			(at 0.61722 -12.75334 180)
			(size 0.3048 0.3048)
			(layers "F.Cu" "F.Mask" "F.Paste")
			(net "M_B_DQ2")
		)
		(pad "B37" smd circle
			(at 1.68402 -12.63904 180)
			(size 0.3048 0.3048)
			(layers "F.Cu" "F.Mask" "F.Paste")
			(net "M_B_DQS_DN0")
		)
		(pad "B39" smd circle
			(at 2.61112 -12.64158 180)
			(size 0.3048 0.3048)
			(layers "F.Cu" "F.Mask" "F.Paste")
			(net "M_B_DQ0")
		)
		(pad "B41" smd circle
			(at 3.63982 -12.80668 180)
			(size 0.3048 0.3048)
			(layers "F.Cu" "F.Mask" "F.Paste")
			(net "GND")
		)
		(pad "B44" smd circle
			(at 5.12064 -12.75334 180)
			(size 0.3048 0.3048)
			(layers "F.Cu" "F.Mask" "F.Paste")
			(net "Net_1363")
		)
		(pad "B46" smd circle
			(at 6.18744 -12.63904 180)
			(size 0.3048 0.3048)
			(layers "F.Cu" "F.Mask" "F.Paste")
			(net "Net_277")
		)
		(pad "B48" smd circle
			(at 7.11454 -12.64158 180)
			(size 0.3048 0.3048)
			(layers "F.Cu" "F.Mask" "F.Paste")
			(net "CPU_GBE_TX_DN0")
		)
		(pad "B50" smd circle
			(at 8.14324 -12.80668 180)
			(size 0.3048 0.3048)
			(layers "F.Cu" "F.Mask" "F.Paste")
			(net "CLK_100M_CPU_GBE_DP")
		)
		(pad "B53" smd circle
			(at 9.62406 -12.75334 180)
			(size 0.3048 0.3048)
			(layers "F.Cu" "F.Mask" "F.Paste")
			(net "Net_1349")
		)
		(pad "B55" smd circle
			(at 10.69086 -12.63904 180)
			(size 0.3048 0.3048)
			(layers "F.Cu" "F.Mask" "F.Paste")
			(net "GND")
		)
		(pad "B57" smd circle
			(at 11.61796 -12.64158 180)
			(size 0.3048 0.3048)
			(layers "F.Cu" "F.Mask" "F.Paste")
			(net "SATA2_TX_DP0")
		)
		(pad "BA17" smd circle
			(at -8.17626 6.53542 180)
			(size 0.3048 0.3048)
			(layers "F.Cu" "F.Mask" "F.Paste")
			(net "GND")
		)
		(pad "BA21" smd circle
			(at -6.18998 6.91642 180)
			(size 0.3048 0.3048)
			(layers "F.Cu" "F.Mask" "F.Paste")
			(net "M_A_CK_DP0")
		)
		(pad "BA23" smd circle
			(at -5.48894 6.91642 180)
			(size 0.3048 0.3048)
			(layers "F.Cu" "F.Mask" "F.Paste")
			(net "M_A_MA13")
		)
		(pad "BA25" smd circle
			(at -4.2037 6.53542 180)
			(size 0.3048 0.3048)
			(layers "F.Cu" "F.Mask" "F.Paste")
			(net "M_A_R_RESET#")
		)
		(pad "BA26" smd circle
			(at -3.50266 6.53542 180)
			(size 0.3048 0.3048)
			(layers "F.Cu" "F.Mask" "F.Paste")
			(net "M_A_CMDPU")
		)
		(pad "BA29" smd circle
			(at -2.21742 6.91642 180)
			(size 0.3048 0.3048)
			(layers "F.Cu" "F.Mask" "F.Paste")
			(net "GND")
		)
		(pad "BA30" smd circle
			(at -1.51638 6.91642 180)
			(size 0.3048 0.3048)
			(layers "F.Cu" "F.Mask" "F.Paste")
			(net "M_A_DQ33")
		)
		(pad "BA32" smd circle
			(at -0.23114 6.53542 180)
			(size 0.3048 0.3048)
			(layers "F.Cu" "F.Mask" "F.Paste")
			(net "M_A_DQ32")
		)
		(pad "BA34" smd circle
			(at 0.4699 6.53542 180)
			(size 0.3048 0.3048)
			(layers "F.Cu" "F.Mask" "F.Paste")
			(net "GND")
		)
		(pad "BA37" smd circle
			(at 1.75514 6.91642 180)
			(size 0.3048 0.3048)
			(layers "F.Cu" "F.Mask" "F.Paste")
			(net "P1V0")
		)
		(pad "BA38" smd circle
			(at 2.45618 6.91642 180)
			(size 0.3048 0.3048)
			(layers "F.Cu" "F.Mask" "F.Paste")
			(net "PCIE_OBS_N")
		)
		(pad "BA41" smd circle
			(at 3.74142 6.53542 180)
			(size 0.3048 0.3048)
			(layers "F.Cu" "F.Mask" "F.Paste")
			(net "Net_1369")
		)
		(pad "BA42" smd circle
			(at 4.44246 6.53542 180)
			(size 0.3048 0.3048)
			(layers "F.Cu" "F.Mask" "F.Paste")
			(net "GND")
		)
		(pad "BA45" smd circle
			(at 5.7277 6.91642 180)
			(size 0.3048 0.3048)
			(layers "F.Cu" "F.Mask" "F.Paste")
			(net "USB_P1_DP")
		)
		(pad "BA46" smd circle
			(at 6.42874 6.91642 180)
			(size 0.3048 0.3048)
			(layers "F.Cu" "F.Mask" "F.Paste")
			(net "Net_618")
		)
		(pad "BA49" smd circle
			(at 7.71398 6.53542 180)
			(size 0.3048 0.3048)
			(layers "F.Cu" "F.Mask" "F.Paste")
			(net "GND")
		)
		(pad "BA50" smd circle
			(at 8.41502 6.53542 180)
			(size 0.3048 0.3048)
			(layers "F.Cu" "F.Mask" "F.Paste")
			(net "CLK_96M_CPU_USB_DN")
		)
		(pad "BB2" smd circle
			(at -15.63878 7.32028 180)
			(size 0.3048 0.3048)
			(layers "F.Cu" "F.Mask" "F.Paste")
			(net "M_A_DQS_DP8")
		)
		(pad "BB4" smd circle
			(at -14.89964 7.2898 180)
			(size 0.3048 0.3048)
			(layers "F.Cu" "F.Mask" "F.Paste")
			(net "M_A_DQS_DN8")
		)
		(pad "BB5" smd circle
			(at -14.20368 7.19836 180)
			(size 0.3048 0.3048)
			(layers "F.Cu" "F.Mask" "F.Paste")
			(net "GND")
		)
		(pad "BB17" smd circle
			(at -8.17626 7.29742 180)
			(size 0.3048 0.3048)
			(layers "F.Cu" "F.Mask" "F.Paste")
			(net "GND")
		)
		(pad "BB19" smd circle
			(at -7.47522 7.29742 180)
			(size 0.3048 0.3048)
			(layers "F.Cu" "F.Mask" "F.Paste")
			(net "M_A_CK_DP3")
		)
		(pad "BB25" smd circle
			(at -4.2037 7.29742 180)
			(size 0.3048 0.3048)
			(layers "F.Cu" "F.Mask" "F.Paste")
			(net "M_A_CS_N1")
		)
		(pad "BB26" smd circle
			(at -3.50266 7.29742 180)
			(size 0.3048 0.3048)
			(layers "F.Cu" "F.Mask" "F.Paste")
			(net "M_A_ODT1")
		)
		(pad "BB32" smd circle
			(at -0.23114 7.29742 180)
			(size 0.3048 0.3048)
			(layers "F.Cu" "F.Mask" "F.Paste")
			(net "M_A_DQ36")
		)
		(pad "BB34" smd circle
			(at 0.4699 7.29742 180)
			(size 0.3048 0.3048)
			(layers "F.Cu" "F.Mask" "F.Paste")
			(net "GND")
		)
		(pad "BB41" smd circle
			(at 3.74142 7.29742 180)
			(size 0.3048 0.3048)
			(layers "F.Cu" "F.Mask" "F.Paste")
			(net "Net_1370")
		)
		(pad "BB42" smd circle
			(at 4.44246 7.29742 180)
			(size 0.3048 0.3048)
			(layers "F.Cu" "F.Mask" "F.Paste")
			(net "Net_1368")
		)
		(pad "BB49" smd circle
			(at 7.71398 7.29742 180)
			(size 0.3048 0.3048)
			(layers "F.Cu" "F.Mask" "F.Paste")
			(net "CLK_100M_CLKBUFF_PCIE_DP")
		)
		(pad "BB50" smd circle
			(at 8.41502 7.29742 180)
			(size 0.3048 0.3048)
			(layers "F.Cu" "F.Mask" "F.Paste")
			(net "CLK_96M_CPU_USB_DP")
		)
		(pad "BB53" smd circle
			(at 9.53516 7.47522 180)
			(size 0.3048 0.3048)
			(layers "F.Cu" "F.Mask" "F.Paste")
			(net "GND")
		)
		(pad "BB54" smd circle
			(at 10.29716 7.47522 180)
			(size 0.3048 0.3048)
			(layers "F.Cu" "F.Mask" "F.Paste")
			(net "GND")
		)
		(pad "BB56" smd circle
			(at 11.05916 7.47522 180)
			(size 0.3048 0.3048)
			(layers "F.Cu" "F.Mask" "F.Paste")
			(net "GND")
		)
		(pad "BB57" smd circle
			(at 11.82116 7.47522 180)
			(size 0.3048 0.3048)
			(layers "F.Cu" "F.Mask" "F.Paste")
			(net "GND")
		)
		(pad "BB59" smd circle
			(at 12.58316 7.47522 180)
			(size 0.3048 0.3048)
			(layers "F.Cu" "F.Mask" "F.Paste")
			(net "PROCESSOR_HOT#")
		)
		(pad "BB60" smd circle
			(at 13.34516 7.47522 180)
			(size 0.3048 0.3048)
			(layers "F.Cu" "F.Mask" "F.Paste")
			(net "SVID_CLK_R")
		)
		(pad "BB62" smd circle
			(at 14.20368 7.0104 180)
			(size 0.3048 0.3048)
			(layers "F.Cu" "F.Mask" "F.Paste")
			(net "GND")
		)
		(pad "BB63" smd circle
			(at 14.89964 7.10692 180)
			(size 0.3048 0.3048)
			(layers "F.Cu" "F.Mask" "F.Paste")
			(net "XDP_DFX_PORT10")
		)
		(pad "BB65" smd circle
			(at 15.64132 7.11454 180)
			(size 0.3048 0.3048)
			(layers "F.Cu" "F.Mask" "F.Paste")
			(net "GND")
		)
		(pad "BB66" smd oval
			(at 16.24838 7.46252 180)
			(size 0.3429 0.254)
			(layers "F.Cu" "F.Mask" "F.Paste")
			(net "GND")
		)
		(pad "BC1" smd oval
			(at -16.24838 7.6708 180)
			(size 0.3429 0.254)
			(layers "F.Cu" "F.Mask" "F.Paste")
			(net "M_A_ECC6")
		)
		(pad "BC3" smd circle
			(at -15.24254 7.90194 180)
			(size 0.3048 0.3048)
			(layers "F.Cu" "F.Mask" "F.Paste")
			(net "M_A_ECC7")
		)
		(pad "BC5" smd circle
			(at -14.08176 7.89178 180)
			(size 0.3048 0.3048)
			(layers "F.Cu" "F.Mask" "F.Paste")
			(net "GND")
		)
		(pad "BC7" smd circle
			(at -13.34516 7.71398 180)
			(size 0.3048 0.3048)
			(layers "F.Cu" "F.Mask" "F.Paste")
			(net "PV_VDDR")
		)
		(pad "BC8" smd circle
			(at -12.58316 7.71398 180)
			(size 0.3048 0.3048)
			(layers "F.Cu" "F.Mask" "F.Paste")
			(net "M_A_BS2")
		)
		(pad "BC10" smd circle
			(at -11.82116 7.71398 180)
			(size 0.3048 0.3048)
			(layers "F.Cu" "F.Mask" "F.Paste")
			(net "PV_VDDR")
		)
		(pad "BC11" smd circle
			(at -11.05916 7.71398 180)
			(size 0.3048 0.3048)
			(layers "F.Cu" "F.Mask" "F.Paste")
			(net "M_A_MA14")
		)
		(pad "BC13" smd circle
			(at -10.29716 7.71398 180)
			(size 0.3048 0.3048)
			(layers "F.Cu" "F.Mask" "F.Paste")
			(net "PV_VDDR")
		)
		(pad "BC15" smd circle
			(at -9.4615 7.67842 180)
			(size 0.3048 0.3048)
			(layers "F.Cu" "F.Mask" "F.Paste")
			(net "PV_VDDR")
		)
		(pad "BC21" smd circle
			(at -6.18998 7.67842 180)
			(size 0.3048 0.3048)
			(layers "F.Cu" "F.Mask" "F.Paste")
			(net "M_A_CK_DN0")
		)
		(pad "BC23" smd circle
			(at -5.48894 7.67842 180)
			(size 0.3048 0.3048)
			(layers "F.Cu" "F.Mask" "F.Paste")
			(net "M_A_WE#")
		)
		(pad "BC29" smd circle
			(at -2.21742 7.67842 180)
			(size 0.3048 0.3048)
			(layers "F.Cu" "F.Mask" "F.Paste")
			(net "M_A_DQS_DN4")
		)
		(pad "BC30" smd circle
			(at -1.51638 7.67842 180)
			(size 0.3048 0.3048)
			(layers "F.Cu" "F.Mask" "F.Paste")
			(net "GND")
		)
		(pad "BC37" smd circle
			(at 1.75514 7.67842 180)
			(size 0.3048 0.3048)
			(layers "F.Cu" "F.Mask" "F.Paste")
			(net "GND")
		)
		(pad "BC38" smd circle
			(at 2.45618 7.67842 180)
			(size 0.3048 0.3048)
			(layers "F.Cu" "F.Mask" "F.Paste")
			(net "PCIE_OBS_P")
		)
		(pad "BC45" smd circle
			(at 5.7277 7.67842 180)
			(size 0.3048 0.3048)
			(layers "F.Cu" "F.Mask" "F.Paste")
			(net "USB_P1_DN")
		)
		(pad "BC46" smd circle
			(at 6.42874 7.67842 180)
			(size 0.3048 0.3048)
			(layers "F.Cu" "F.Mask" "F.Paste")
			(net "GND")
		)
		(pad "BC62" smd circle
			(at 14.01318 7.68858 180)
			(size 0.3048 0.3048)
			(layers "F.Cu" "F.Mask" "F.Paste")
			(net "SVID_ALERT#")
		)
		(pad "BC64" smd circle
			(at 15.24762 7.71906 180)
			(size 0.3048 0.3048)
			(layers "F.Cu" "F.Mask" "F.Paste")
			(net "XDP_DFX_PORT0")
		)
		(pad "BD2" smd circle
			(at -15.75308 8.38708 180)
			(size 0.3048 0.3048)
			(layers "F.Cu" "F.Mask" "F.Paste")
			(net "M_A_ECC2")
		)
		(pad "BD4" smd circle
			(at -14.7955 8.44042 180)
			(size 0.3048 0.3048)
			(layers "F.Cu" "F.Mask" "F.Paste")
			(net "M_A_ECC3")
		)
		(pad "BD7" smd circle
			(at -13.34516 8.41502 180)
			(size 0.3048 0.3048)
			(layers "F.Cu" "F.Mask" "F.Paste")
			(net "M_A_MA12")
		)
		(pad "BD8" smd circle
			(at -12.58316 8.41502 180)
			(size 0.3048 0.3048)
			(layers "F.Cu" "F.Mask" "F.Paste")
			(net "M_A_MA8")
		)
		(pad "BD10" smd circle
			(at -11.82116 8.41502 180)
			(size 0.3048 0.3048)
			(layers "F.Cu" "F.Mask" "F.Paste")
			(net "M_A_MA6")
		)
	)
)
